FILE_TYPE = CONNECTIVITY;
{Allegro Design Entry HDL 17.4-2019 S026 (4007227) 1/17/2022}
"PAGE_NUMBER" = 136;
0"NC";
1"GND\g";
2"GND\g";
3"GND\g";
4"GND\g";
5"GND\g";
6"GND\g";
7"GND\g";
8"GND\g";
9"I3C_SPD_DDRGL_CPU1_SDA";
10"I3C_SPD_DDRGL_CPU1_BYPASS_SCL";
11"I3C_SPD_DDRGL_CPU1_SCL";
12"I3C_SPD_DDRGL_CPU1_BYPASS_SDA";
13"I3C_1_SPD_DDRGL_CPU1_R_SDA";
14"I3C_1_SPD_DDRGL_CPU1_R_SCL";
15"FM_I3C_CPU1_MUX1_OE_N";
16"I3C_SPD_DDRAF_CPU1_BYPASS_SDA";
17"I3C_SPD_DDRAF_CPU1_BYPASS_SCL";
18"I3C_SPD_DDRAF_CPU1_SCL";
19"I3C_SPD_DDRAF_CPU1_SDA";
20"P3V3_AUX\g";
21"P3V3_AUX\g";
22"P3V3_AUX\g";
23"P3V3_AUX\g";
24"PVDD11_S3_P1\g";
25"PVDD11_S3_P1\g";
26"PVDD11_S3_P0\g";
27"PVDD11_S3_P0\g";
28"PVDD11_S3_P1\g";
29"PVDD11_S3_P1\g";
30"PVDD11_S3_P0\g";
31"PVDD11_S3_P0\g";
32"I3C_0_SPD_DDRAF_CPU1_R_SCL";
33"I3C_0_SPD_DDRAF_CPU1_R_SDA";
34"I3C_SPD_DDRGL_CPU0_SDA";
35"I3C_SPD_DDRGL_CPU0_BYPASS_SCL";
36"I3C_SPD_DDRGL_CPU0_BYPASS_SDA";
37"I3C_SPD_DDRGL_CPU0_SCL";
38"I3C_1_SPD_DDRGL_CPU0_R_SDA";
39"I3C_1_SPD_DDRGL_CPU0_R_SCL";
40"I3C_SPD_DDRAF_CPU0_SDA";
41"I3C_SPD_DDRAF_CPU0_SCL";
42"I3C_SPD_DDRAF_CPU0_BYPASS_SDA";
43"I3C_0_SPD_DDRAF_CPU0_R_SDA";
44"I3C_0_SPD_DDRAF_CPU0_R_SCL";
45"I3C_1_SPD_DDRGL_CPU1_SCL";
46"I3C_SCM_3_R_SDA";
47"I3C_SPD_DDRAF_CPU1_LVC1_SDA";
48"I3C_SPD_DDRAF_CPU1_LVC1_SCL";
49"I3C_SCM_2_R_SDA";
50"FM_I3C_CPU1_MUX0_SEL";
51"FM_I3C_CPU1_MUX0_OE_N";
52"I3C_SCM_2_R_SCL";
53"I3C_SPD_DDRGL_CPU0_LVC1_SDA";
54"I3C_SPD_DDRGL_CPU0_LVC1_SCL";
55"I3C_1_SPD_DDRGL_CPU0_SCL";
56"I3C_SPD_DDRAF_CPU0_BYPASS_SCL";
57"I3C_SPD_DDRAF_CPU0_LVC1_SDA";
58"I3C_SPD_DDRAF_CPU0_LVC1_SCL";
59"FM_I3C_CPU0_MUX1_OE_N";
60"I3C_SCM_0_R_SDA";
61"I3C_SCM_0_R_SCL";
62"I3C_0_SPD_DDRAF_CPU0_SDA";
63"I3C_0_SPD_DDRAF_CPU0_SCL";
64"I3C_SCM_1_R_SCL";
65"I3C_SCM_1_R_SDA";
66"I3C_SCM_3_R_SCL";
67"I3C_SPD_DDRGL_CPU1_LVC1_SCL";
68"I3C_SPD_DDRGL_CPU1_LVC1_SDA";
69"I3C_1_SPD_DDRGL_CPU0_SDA";
70"I3C_1_SPD_DDRGL_CPU1_SDA";
71"I3C_0_SPD_DDRAF_CPU1_SCL";
72"I3C_0_SPD_DDRAF_CPU1_SDA";
73"FM_I3C_CPU0_MUX0_OE_N";
74"FM_I3C_CPU0_MUX0_SEL";
75"FM_I3C_CPU1_MUX1_SEL";
76"FM_I3C_CPU0_MUX1_SEL";
%"Q_RES"
"1","(-6075,5725)","2","pure_quanta","I100";
;
LOCATION"R427"
$SEC"1"
CDS_SEC"1"
VALUE"0"
CDS_LIB"pure_quanta"
WATTAGE"1/16W"
MATERIAL"CHIP"
TOLERANCE"5%"
PACK_TYPE"0402LF"
PART_NUMBER"CS00002JB13";
"B"
$PN"2"43;
"A"
$PN"1"62;
%"Q_RES"
"1","(-6050,4375)","2","pure_quanta","I103";
;
LOCATION"R428"
$SEC"1"
CDS_SEC"1"
VALUE"0"
CDS_LIB"pure_quanta"
WATTAGE"1/16W"
MATERIAL"CHIP"
TOLERANCE"5%"
PACK_TYPE"0402LF"
PART_NUMBER"CS00002JB13";
"B"
$PN"2"39;
"A"
$PN"1"55;
%"Q_RES"
"1","(-6050,4325)","2","pure_quanta","I104";
;
LOCATION"R429"
$SEC"1"
CDS_SEC"1"
VALUE"0"
CDS_LIB"pure_quanta"
WATTAGE"1/16W"
MATERIAL"CHIP"
TOLERANCE"5%"
PACK_TYPE"0402LF"
PART_NUMBER"CS00002JB13";
"B"
$PN"2"38;
"A"
$PN"1"69;
%"Q_RES"
"1","(-6050,2800)","2","pure_quanta","I107";
;
LOCATION"R565"
$SEC"1"
CDS_SEC"1"
VALUE"0"
CDS_LIB"pure_quanta"
WATTAGE"1/16W"
MATERIAL"CHIP"
TOLERANCE"5%"
PACK_TYPE"0402LF"
PART_NUMBER"CS00002JB13";
"B"
$PN"2"33;
"A"
$PN"1"72;
%"Q_RES"
"1","(-6050,2850)","2","pure_quanta","I108";
;
LOCATION"R564"
$SEC"1"
CDS_SEC"1"
VALUE"0"
CDS_LIB"pure_quanta"
WATTAGE"1/16W"
MATERIAL"CHIP"
TOLERANCE"5%"
PACK_TYPE"0402LF"
PART_NUMBER"CS00002JB13";
"B"
$PN"2"32;
"A"
$PN"1"71;
%"Q_RES"
"1","(-5975,1400)","2","pure_quanta","I111";
;
LOCATION"R566"
$SEC"1"
CDS_SEC"1"
VALUE"0"
CDS_LIB"pure_quanta"
WATTAGE"1/16W"
MATERIAL"CHIP"
TOLERANCE"5%"
PACK_TYPE"0402LF"
PART_NUMBER"CS00002JB13";
"B"
$PN"2"14;
"A"
$PN"1"45;
%"Q_RES"
"1","(-5975,1350)","2","pure_quanta","I112";
;
LOCATION"R567"
$SEC"1"
CDS_SEC"1"
VALUE"0"
CDS_LIB"pure_quanta"
WATTAGE"1/16W"
MATERIAL"CHIP"
TOLERANCE"5%"
PACK_TYPE"0402LF"
PART_NUMBER"CS00002JB13";
"B"
$PN"2"13;
"A"
$PN"1"70;
%"Q_RES"
"1","(-6100,5325)","0","pure_quanta","I123";
;
LOCATION"R2310"
$SEC"1"
CDS_SEC"1"
VALUE"0"
MATERIAL"EMPTY"
CDS_LIB"pure_quanta"
WATTAGE"1/16W"
TOLERANCE"5%"
PACK_TYPE"0402LF"
PART_NUMBER"CS00002JB13";
"B"
$PN"2"56;
"A"
$PN"1"44;
%"Q_RES"
"1","(-6100,5275)","0","pure_quanta","I124";
;
LOCATION"R2311"
$SEC"1"
CDS_SEC"1"
MATERIAL"EMPTY"
VALUE"0"
CDS_LIB"pure_quanta"
WATTAGE"1/16W"
TOLERANCE"5%"
PACK_TYPE"0402LF"
PART_NUMBER"CS00002JB13";
"B"
$PN"2"42;
"A"
$PN"1"43;
%"Q_RES"
"1","(-3175,5325)","0","pure_quanta","I131";
;
LOCATION"R1330"
$SEC"1"
CDS_SEC"1"
VALUE"0"
MATERIAL"EMPTY"
CDS_LIB"pure_quanta"
WATTAGE"1/16W"
TOLERANCE"5%"
PACK_TYPE"0402LF"
PART_NUMBER"CS00002JB13";
"B"
$PN"2"41;
"A"
$PN"1"56;
%"Q_RES"
"1","(-3175,5275)","0","pure_quanta","I132";
;
LOCATION"R1331"
$SEC"1"
CDS_SEC"1"
MATERIAL"EMPTY"
VALUE"0"
CDS_LIB"pure_quanta"
WATTAGE"1/16W"
TOLERANCE"5%"
PACK_TYPE"0402LF"
PART_NUMBER"CS00002JB13";
"B"
$PN"2"40;
"A"
$PN"1"42;
%"Q_RES"
"1","(-3125,3875)","0","pure_quanta","I133";
;
LOCATION"R1333"
$SEC"1"
CDS_SEC"1"
MATERIAL"EMPTY"
VALUE"0"
CDS_LIB"pure_quanta"
WATTAGE"1/16W"
TOLERANCE"5%"
PACK_TYPE"0402LF"
PART_NUMBER"CS00002JB13";
"B"
$PN"2"34;
"A"
$PN"1"36;
%"Q_RES"
"1","(-3125,3925)","0","pure_quanta","I134";
;
LOCATION"R1332"
$SEC"1"
CDS_SEC"1"
MATERIAL"EMPTY"
VALUE"0"
CDS_LIB"pure_quanta"
WATTAGE"1/16W"
TOLERANCE"5%"
PACK_TYPE"0402LF"
PART_NUMBER"CS00002JB13";
"B"
$PN"2"37;
"A"
$PN"1"35;
%"Q_RES"
"1","(-6050,3925)","0","pure_quanta","I135";
;
LOCATION"R986"
$SEC"1"
CDS_SEC"1"
MATERIAL"EMPTY"
VALUE"0"
CDS_LIB"pure_quanta"
WATTAGE"1/16W"
TOLERANCE"5%"
PACK_TYPE"0402LF"
PART_NUMBER"CS00002JB13";
"B"
$PN"2"35;
"A"
$PN"1"39;
%"Q_RES"
"1","(-6050,3875)","0","pure_quanta","I136";
;
LOCATION"R987"
$SEC"1"
CDS_SEC"1"
MATERIAL"EMPTY"
VALUE"0"
CDS_LIB"pure_quanta"
WATTAGE"1/16W"
TOLERANCE"5%"
PACK_TYPE"0402LF"
PART_NUMBER"CS00002JB13";
"B"
$PN"2"36;
"A"
$PN"1"38;
%"Q_RES"
"1","(-6000,2350)","0","pure_quanta","I137";
;
LOCATION"R989"
$SEC"1"
CDS_SEC"1"
VALUE"0"
MATERIAL"EMPTY"
CDS_LIB"pure_quanta"
WATTAGE"1/16W"
TOLERANCE"5%"
PACK_TYPE"0402LF"
PART_NUMBER"CS00002JB13";
"B"
$PN"2"16;
"A"
$PN"1"33;
%"Q_RES"
"1","(-6000,2400)","0","pure_quanta","I138";
;
LOCATION"R988"
$SEC"1"
CDS_SEC"1"
VALUE"0"
MATERIAL"EMPTY"
CDS_LIB"pure_quanta"
WATTAGE"1/16W"
TOLERANCE"5%"
PACK_TYPE"0402LF"
PART_NUMBER"CS00002JB13";
"B"
$PN"2"17;
"A"
$PN"1"32;
%"Q_RES"
"1","(-3075,2400)","0","pure_quanta","I139";
;
LOCATION"R1334"
$SEC"1"
CDS_SEC"1"
MATERIAL"EMPTY"
VALUE"0"
CDS_LIB"pure_quanta"
WATTAGE"1/16W"
TOLERANCE"5%"
PACK_TYPE"0402LF"
PART_NUMBER"CS00002JB13";
"B"
$PN"2"18;
"A"
$PN"1"17;
%"Q_RES"
"1","(-3075,2350)","0","pure_quanta","I140";
;
LOCATION"R1335"
$SEC"1"
CDS_SEC"1"
MATERIAL"EMPTY"
VALUE"0"
CDS_LIB"pure_quanta"
WATTAGE"1/16W"
TOLERANCE"5%"
PACK_TYPE"0402LF"
PART_NUMBER"CS00002JB13";
"B"
$PN"2"19;
"A"
$PN"1"16;
%"Q_RES"
"1","(-5950,900)","0","pure_quanta","I141";
;
LOCATION"R991"
$SEC"1"
CDS_SEC"1"
MATERIAL"EMPTY"
VALUE"0"
CDS_LIB"pure_quanta"
WATTAGE"1/16W"
TOLERANCE"5%"
PACK_TYPE"0402LF"
PART_NUMBER"CS00002JB13";
"B"
$PN"2"12;
"A"
$PN"1"13;
%"Q_RES"
"1","(-5950,950)","0","pure_quanta","I142";
;
LOCATION"R990"
$SEC"1"
CDS_SEC"1"
MATERIAL"EMPTY"
VALUE"0"
CDS_LIB"pure_quanta"
WATTAGE"1/16W"
TOLERANCE"5%"
PACK_TYPE"0402LF"
PART_NUMBER"CS00002JB13";
"B"
$PN"2"10;
"A"
$PN"1"14;
%"Q_RES"
"1","(-3025,950)","0","pure_quanta","I143";
;
LOCATION"R1336"
$SEC"1"
CDS_SEC"1"
MATERIAL"EMPTY"
VALUE"0"
CDS_LIB"pure_quanta"
WATTAGE"1/16W"
TOLERANCE"5%"
PACK_TYPE"0402LF"
PART_NUMBER"CS00002JB13";
"B"
$PN"2"11;
"A"
$PN"1"10;
%"Q_RES"
"1","(-3025,900)","0","pure_quanta","I144";
;
LOCATION"R1337"
$SEC"1"
CDS_SEC"1"
MATERIAL"EMPTY"
VALUE"0"
CDS_LIB"pure_quanta"
WATTAGE"1/16W"
TOLERANCE"5%"
PACK_TYPE"0402LF"
PART_NUMBER"CS00002JB13";
"B"
$PN"2"9;
"A"
$PN"1"12;
%"Q_RES"
"2","(-3450,6100)","0","pure_quanta","I145";
;
LOCATION"R5006"
$SEC"1"
CDS_SEC"1"
WATTAGE"1/16W"
PACK_TYPE"0402LF"
VALUE"1K"
TOLERANCE"1%"
MATERIAL"EMPTY"
CDS_LIB"pure_quanta"
PART_NUMBER"CS21002FB06";
"A"
$PN"1"31;
"B"
$PN"2"58;
%"VCC_CORE"
"1","(-3450,6375)","0","pure_quanta_power","I146";
;
HDL_POWER"PVDD11_S3_P0"
CDS_LIB"pure_quanta_power";
"A"31;
%"Q_RES"
"2","(-3650,6100)","0","pure_quanta","I147";
;
LOCATION"R5007"
$SEC"1"
CDS_SEC"1"
WATTAGE"1/16W"
PACK_TYPE"0402LF"
TOLERANCE"1%"
MATERIAL"EMPTY"
VALUE"1K"
CDS_LIB"pure_quanta"
PART_NUMBER"CS21002FB06";
"A"
$PN"1"31;
"B"
$PN"2"57;
%"Q_RES"
"2","(-3450,4700)","0","pure_quanta","I148";
;
LOCATION"R5008"
$SEC"1"
CDS_SEC"1"
TOLERANCE"1%"
VALUE"1K"
PACK_TYPE"0402LF"
MATERIAL"EMPTY"
WATTAGE"1/16W"
CDS_LIB"pure_quanta"
PART_NUMBER"CS21002FB06";
"A"
$PN"1"30;
"B"
$PN"2"54;
%"VCC_CORE"
"1","(-3450,4975)","0","pure_quanta_power","I149";
;
HDL_POWER"PVDD11_S3_P0"
CDS_LIB"pure_quanta_power";
"A"30;
%"Q_RES"
"2","(-3650,4700)","0","pure_quanta","I150";
;
LOCATION"R5009"
$SEC"1"
CDS_SEC"1"
TOLERANCE"1%"
WATTAGE"1/16W"
PACK_TYPE"0402LF"
MATERIAL"EMPTY"
VALUE"1K"
CDS_LIB"pure_quanta"
PART_NUMBER"CS21002FB06";
"A"
$PN"1"30;
"B"
$PN"2"53;
%"Q_RES"
"2","(-3450,3175)","0","pure_quanta","I151";
;
LOCATION"R5010"
$SEC"1"
CDS_SEC"1"
WATTAGE"1/16W"
TOLERANCE"1%"
PACK_TYPE"0402LF"
VALUE"1K"
MATERIAL"EMPTY"
CDS_LIB"pure_quanta"
PART_NUMBER"CS21002FB06";
"A"
$PN"1"29;
"B"
$PN"2"48;
%"Q_RES"
"2","(-3650,3175)","0","pure_quanta","I152";
;
LOCATION"R5011"
$SEC"1"
CDS_SEC"1"
PACK_TYPE"0402LF"
MATERIAL"EMPTY"
VALUE"1K"
WATTAGE"1/16W"
TOLERANCE"1%"
CDS_LIB"pure_quanta"
PART_NUMBER"CS21002FB06";
"A"
$PN"1"29;
"B"
$PN"2"47;
%"VCC_CORE"
"1","(-3450,3450)","0","pure_quanta_power","I153";
;
HDL_POWER"PVDD11_S3_P1"
CDS_LIB"pure_quanta_power";
"A"29;
%"Q_RES"
"2","(-3650,1725)","0","pure_quanta","I154";
;
LOCATION"R5013"
$SEC"1"
CDS_SEC"1"
TOLERANCE"1%"
VALUE"1K"
MATERIAL"EMPTY"
WATTAGE"1/16W"
PACK_TYPE"0402LF"
CDS_LIB"pure_quanta"
PART_NUMBER"CS21002FB06";
"A"
$PN"1"28;
"B"
$PN"2"68;
%"VCC_CORE"
"1","(-3450,2000)","0","pure_quanta_power","I155";
;
HDL_POWER"PVDD11_S3_P1"
CDS_LIB"pure_quanta_power";
"A"28;
%"Q_RES"
"2","(-3450,1725)","0","pure_quanta","I156";
;
LOCATION"R5012"
$SEC"1"
CDS_SEC"1"
PACK_TYPE"0402LF"
VALUE"1K"
MATERIAL"EMPTY"
TOLERANCE"1%"
WATTAGE"1/16W"
CDS_LIB"pure_quanta"
PART_NUMBER"CS21002FB06";
"A"
$PN"1"28;
"B"
$PN"2"67;
%"Q_RES"
"2","(-5650,6175)","0","pure_quanta","I157";
;
LOCATION"R5015"
$SEC"1"
CDS_SEC"1"
VALUE"1K"
TOLERANCE"1%"
MATERIAL"EMPTY"
WATTAGE"1/16W"
PACK_TYPE"0402LF"
CDS_LIB"pure_quanta"
PART_NUMBER"CS21002FB06";
"A"
$PN"1"27;
"B"
$PN"2"60;
%"VCC_CORE"
"1","(-5450,6475)","0","pure_quanta_power","I158";
;
HDL_POWER"PVDD11_S3_P0"
CDS_LIB"pure_quanta_power";
"A"27;
%"Q_RES"
"2","(-5450,6175)","0","pure_quanta","I159";
;
LOCATION"R5014"
$SEC"1"
CDS_SEC"1"
VALUE"1K"
MATERIAL"EMPTY"
WATTAGE"1/16W"
PACK_TYPE"0402LF"
TOLERANCE"1%"
CDS_LIB"pure_quanta"
PART_NUMBER"CS21002FB06";
"A"
$PN"1"27;
"B"
$PN"2"61;
%"VCC_CORE"
"1","(-5450,4900)","0","pure_quanta_power","I160";
;
HDL_POWER"PVDD11_S3_P0"
CDS_LIB"pure_quanta_power";
"A"26;
%"Q_RES"
"2","(-5650,4700)","0","pure_quanta","I161";
;
LOCATION"R5017"
$SEC"1"
CDS_SEC"1"
WATTAGE"1/16W"
VALUE"1K"
TOLERANCE"1%"
PACK_TYPE"0402LF"
MATERIAL"EMPTY"
CDS_LIB"pure_quanta"
PART_NUMBER"CS21002FB06";
"A"
$PN"1"26;
"B"
$PN"2"65;
%"Q_RES"
"2","(-5450,4700)","0","pure_quanta","I162";
;
LOCATION"R5016"
$SEC"1"
CDS_SEC"1"
TOLERANCE"1%"
VALUE"1K"
PACK_TYPE"0402LF"
MATERIAL"EMPTY"
WATTAGE"1/16W"
CDS_LIB"pure_quanta"
PART_NUMBER"CS21002FB06";
"A"
$PN"1"26;
"B"
$PN"2"64;
%"Q_RES"
"2","(-5450,3175)","0","pure_quanta","I163";
;
LOCATION"R5018"
$SEC"1"
CDS_SEC"1"
PACK_TYPE"0402LF"
VALUE"1K"
TOLERANCE"1%"
WATTAGE"1/16W"
MATERIAL"EMPTY"
CDS_LIB"pure_quanta"
PART_NUMBER"CS21002FB06";
"A"
$PN"1"25;
"B"
$PN"2"52;
%"Q_RES"
"2","(-5650,3175)","0","pure_quanta","I164";
;
LOCATION"R5019"
$SEC"1"
CDS_SEC"1"
VALUE"1K"
TOLERANCE"1%"
WATTAGE"1/16W"
MATERIAL"EMPTY"
PACK_TYPE"0402LF"
CDS_LIB"pure_quanta"
PART_NUMBER"CS21002FB06";
"A"
$PN"1"25;
"B"
$PN"2"49;
%"VCC_CORE"
"1","(-5450,3375)","0","pure_quanta_power","I165";
;
HDL_POWER"PVDD11_S3_P1"
CDS_LIB"pure_quanta_power";
"A"25;
%"Q_RES"
"2","(-5650,1725)","0","pure_quanta","I166";
;
LOCATION"R5021"
$SEC"1"
CDS_SEC"1"
TOLERANCE"1%"
VALUE"1K"
MATERIAL"EMPTY"
WATTAGE"1/16W"
PACK_TYPE"0402LF"
CDS_LIB"pure_quanta"
PART_NUMBER"CS21002FB06";
"A"
$PN"1"24;
"B"
$PN"2"46;
%"Q_RES"
"2","(-5450,1725)","0","pure_quanta","I167";
;
LOCATION"R5020"
$SEC"1"
CDS_SEC"1"
TOLERANCE"1%"
VALUE"1K"
PACK_TYPE"0402LF"
MATERIAL"EMPTY"
WATTAGE"1/16W"
CDS_LIB"pure_quanta"
PART_NUMBER"CS21002FB06";
"A"
$PN"1"24;
"B"
$PN"2"66;
%"VCC_CORE"
"1","(-5450,1925)","0","pure_quanta_power","I168";
;
HDL_POWER"PVDD11_S3_P1"
CDS_LIB"pure_quanta_power";
"A"24;
%"Q_RES"
"1","(-3150,5875)","2","pure_quanta","I31";
;
LOCATION"R1297"
$SEC"1"
CDS_SEC"1"
VALUE"0"
CDS_LIB"pure_quanta"
WATTAGE"1/16W"
MATERIAL"CHIP"
TOLERANCE"5%"
PACK_TYPE"0402LF"
PART_NUMBER"CS00002JB13";
"B"
$PN"2"58;
"A"
$PN"1"41;
%"Q_RES"
"1","(-3150,5825)","2","pure_quanta","I32";
;
LOCATION"R1298"
$SEC"1"
CDS_SEC"1"
VALUE"0"
CDS_LIB"pure_quanta"
WATTAGE"1/16W"
MATERIAL"CHIP"
TOLERANCE"5%"
PACK_TYPE"0402LF"
PART_NUMBER"CS00002JB13";
"B"
$PN"2"57;
"A"
$PN"1"40;
%"Q_RES"
"1","(-3150,4475)","2","pure_quanta","I33";
;
LOCATION"R1299"
$SEC"1"
CDS_SEC"1"
VALUE"0"
CDS_LIB"pure_quanta"
WATTAGE"1/16W"
MATERIAL"CHIP"
TOLERANCE"5%"
PACK_TYPE"0402LF"
PART_NUMBER"CS00002JB13";
"B"
$PN"2"54;
"A"
$PN"1"37;
%"Q_RES"
"1","(-3150,4425)","2","pure_quanta","I34";
;
LOCATION"R1300"
$SEC"1"
CDS_SEC"1"
VALUE"0"
CDS_LIB"pure_quanta"
WATTAGE"1/16W"
MATERIAL"CHIP"
TOLERANCE"5%"
PACK_TYPE"0402LF"
PART_NUMBER"CS00002JB13";
"B"
$PN"2"53;
"A"
$PN"1"34;
%"Q_RES"
"1","(-3200,2950)","2","pure_quanta","I35";
;
LOCATION"R1293"
$SEC"1"
CDS_SEC"1"
VALUE"0"
CDS_LIB"pure_quanta"
WATTAGE"1/16W"
MATERIAL"CHIP"
TOLERANCE"5%"
PACK_TYPE"0402LF"
PART_NUMBER"CS00002JB13";
"B"
$PN"2"48;
"A"
$PN"1"18;
%"Q_RES"
"1","(-3200,2900)","2","pure_quanta","I36";
;
LOCATION"R1294"
$SEC"1"
CDS_SEC"1"
VALUE"0"
CDS_LIB"pure_quanta"
WATTAGE"1/16W"
MATERIAL"CHIP"
TOLERANCE"5%"
PACK_TYPE"0402LF"
PART_NUMBER"CS00002JB13";
"B"
$PN"2"47;
"A"
$PN"1"19;
%"Q_RES"
"1","(-3175,1500)","2","pure_quanta","I37";
;
LOCATION"R1295"
$SEC"1"
CDS_SEC"1"
VALUE"0"
CDS_LIB"pure_quanta"
WATTAGE"1/16W"
MATERIAL"CHIP"
TOLERANCE"5%"
PACK_TYPE"0402LF"
PART_NUMBER"CS00002JB13";
"B"
$PN"2"67;
"A"
$PN"1"11;
%"Q_RES"
"1","(-3175,1450)","2","pure_quanta","I38";
;
LOCATION"R1296"
$SEC"1"
CDS_SEC"1"
VALUE"0"
CDS_LIB"pure_quanta"
WATTAGE"1/16W"
MATERIAL"CHIP"
TOLERANCE"5%"
PACK_TYPE"0402LF"
PART_NUMBER"CS00002JB13";
"B"
$PN"2"68;
"A"
$PN"1"9;
%"PI3CSW12ZUAEX"
"1","(-4775,5775)","0","pure_quanta","I47";
;
LOCATION"U105"
$SEC"1"
CDS_SEC"1"
VALUE"PI3CSW12ZUAEX"
PART_TYPE"SMLF"
MATERIAL"IC"
NEEDS_NO_SIZE"TRUE"
CDS_LMAN_SYM_OUTLINE"-150,200,150,-200"
CDS_LIB"pure_quanta"
PART_NUMBER"AL3CSW12000";
"D+"
$PN"8"58;
"GND"
$PN"5"1;
"1D-"
$PN"2"62;
"VDD"
$PN"10"23;
"S"
$PN"9"74;
"OE# \B"
$PN"6"73;
"D-"
$PN"7"57;
"2D-"
$PN"4"60;
"2D+"
$PN"3"61;
"1D+"
$PN"1"63;
%"UNIVERSAL_GND"
"1","(-4325,5450)","0","pure_quanta_power","I48";
;
CDS_LIB"pure_quanta_power"
HDL_POWER"GND";
"A"1;
%"UNIVERSAL_GND"
"1","(-4275,6000)","0","pure_quanta_power","I49";
;
CDS_LIB"pure_quanta_power"
HDL_POWER"GND";
"A"2;
%"Q_CAP"
"1","(-4275,6200)","0","pure_quanta","I50";
;
LOCATION"C1336"
$SEC"1"
CDS_SEC"1"
VOLTAGE"25V"
VALUE"0.1UF"
TOLERANCE"10%"
MATERIAL"X7R"
PACK_TYPE"0402"
CDS_LIB"pure_quanta"
PART_NUMBER"CH4104K1B00";
"B"
$PN"2"2;
"A"
$PN"1"23;
%"UNIVERSAL_POWER"
"1","(-4350,6475)","2","pure_quanta_power","I51";
;
HDL_POWER"P3V3_AUX"
CDS_LIB"pure_quanta_power";
"A"23;
%"PI3CSW12ZUAEX"
"1","(-4750,4375)","0","pure_quanta","I54";
;
LOCATION"U106"
$SEC"1"
CDS_SEC"1"
PART_TYPE"SMLF"
VALUE"PI3CSW12ZUAEX"
MATERIAL"IC"
NEEDS_NO_SIZE"TRUE"
CDS_LMAN_SYM_OUTLINE"-150,200,150,-200"
CDS_LIB"pure_quanta"
PART_NUMBER"AL3CSW12000";
"D+"
$PN"8"54;
"GND"
$PN"5"4;
"1D-"
$PN"2"69;
"VDD"
$PN"10"22;
"S"
$PN"9"76;
"OE# \B"
$PN"6"59;
"D-"
$PN"7"53;
"2D-"
$PN"4"65;
"2D+"
$PN"3"64;
"1D+"
$PN"1"55;
%"UNIVERSAL_POWER"
"1","(-4325,5075)","2","pure_quanta_power","I55";
;
HDL_POWER"P3V3_AUX"
CDS_LIB"pure_quanta_power";
"A"22;
%"Q_CAP"
"1","(-4250,4800)","0","pure_quanta","I56";
;
LOCATION"C1337"
$SEC"1"
CDS_SEC"1"
MATERIAL"X7R"
TOLERANCE"10%"
PACK_TYPE"0402"
VOLTAGE"25V"
VALUE"0.1UF"
CDS_LIB"pure_quanta"
PART_NUMBER"CH4104K1B00";
"B"
$PN"2"3;
"A"
$PN"1"22;
%"UNIVERSAL_GND"
"1","(-4250,4600)","0","pure_quanta_power","I57";
;
CDS_LIB"pure_quanta_power"
HDL_POWER"GND";
"A"3;
%"UNIVERSAL_GND"
"1","(-4300,4050)","0","pure_quanta_power","I58";
;
CDS_LIB"pure_quanta_power"
HDL_POWER"GND";
"A"4;
%"UNIVERSAL_GND"
"1","(-4300,2525)","0","pure_quanta_power","I59";
;
CDS_LIB"pure_quanta_power"
HDL_POWER"GND";
"A"5;
%"UNIVERSAL_GND"
"1","(-4250,3075)","0","pure_quanta_power","I60";
;
CDS_LIB"pure_quanta_power"
HDL_POWER"GND";
"A"6;
%"Q_CAP"
"1","(-4250,3275)","0","pure_quanta","I61";
;
LOCATION"C1338"
$SEC"1"
CDS_SEC"1"
MATERIAL"X7R"
PACK_TYPE"0402"
VOLTAGE"25V"
TOLERANCE"10%"
VALUE"0.1UF"
CDS_LIB"pure_quanta"
PART_NUMBER"CH4104K1B00";
"B"
$PN"2"6;
"A"
$PN"1"21;
%"UNIVERSAL_POWER"
"1","(-4325,3550)","2","pure_quanta_power","I62";
;
HDL_POWER"P3V3_AUX"
CDS_LIB"pure_quanta_power";
"A"21;
%"PI3CSW12ZUAEX"
"1","(-4750,2850)","0","pure_quanta","I63";
;
LOCATION"U107"
$SEC"1"
CDS_SEC"1"
PART_TYPE"SMLF"
MATERIAL"IC"
VALUE"PI3CSW12ZUAEX"
NEEDS_NO_SIZE"TRUE"
CDS_LMAN_SYM_OUTLINE"-150,200,150,-200"
CDS_LIB"pure_quanta"
PART_NUMBER"AL3CSW12000";
"D+"
$PN"8"48;
"GND"
$PN"5"5;
"1D-"
$PN"2"72;
"VDD"
$PN"10"21;
"S"
$PN"9"50;
"OE# \B"
$PN"6"51;
"D-"
$PN"7"47;
"2D-"
$PN"4"49;
"2D+"
$PN"3"52;
"1D+"
$PN"1"71;
%"UNIVERSAL_GND"
"1","(-4250,1075)","0","pure_quanta_power","I64";
;
CDS_LIB"pure_quanta_power"
HDL_POWER"GND";
"A"7;
%"UNIVERSAL_GND"
"1","(-4200,1625)","0","pure_quanta_power","I65";
;
CDS_LIB"pure_quanta_power"
HDL_POWER"GND";
"A"8;
%"Q_CAP"
"1","(-4200,1825)","0","pure_quanta","I66";
;
LOCATION"C1339"
$SEC"1"
CDS_SEC"1"
VALUE"0.1UF"
PACK_TYPE"0402"
MATERIAL"X7R"
TOLERANCE"10%"
VOLTAGE"25V"
CDS_LIB"pure_quanta"
PART_NUMBER"CH4104K1B00";
"B"
$PN"2"8;
"A"
$PN"1"20;
%"UNIVERSAL_POWER"
"1","(-4275,2100)","2","pure_quanta_power","I67";
;
HDL_POWER"P3V3_AUX"
CDS_LIB"pure_quanta_power";
"A"20;
%"PI3CSW12ZUAEX"
"1","(-4700,1400)","0","pure_quanta","I68";
;
LOCATION"U108"
$SEC"1"
CDS_SEC"1"
MATERIAL"IC"
VALUE"PI3CSW12ZUAEX"
PART_TYPE"SMLF"
CDS_LIB"pure_quanta"
CDS_LMAN_SYM_OUTLINE"-150,200,150,-200"
NEEDS_NO_SIZE"TRUE"
PART_NUMBER"AL3CSW12000";
"D+"
$PN"8"67;
"GND"
$PN"5"7;
"1D-"
$PN"2"70;
"VDD"
$PN"10"20;
"S"
$PN"9"75;
"OE# \B"
$PN"6"15;
"D-"
$PN"7"68;
"2D-"
$PN"4"46;
"2D+"
$PN"3"66;
"1D+"
$PN"1"45;
%"Q_RES"
"1","(-6075,5775)","2","pure_quanta","I99";
;
LOCATION"R426"
$SEC"1"
CDS_SEC"1"
VALUE"0"
CDS_LIB"pure_quanta"
WATTAGE"1/16W"
MATERIAL"CHIP"
TOLERANCE"5%"
PACK_TYPE"0402LF"
PART_NUMBER"CS00002JB13";
"B"
$PN"2"44;
"A"
$PN"1"63;
END.
